# S9S_MB_2U (Grand Teton) — schematic netlist excerpt (pin names and nets, part order shuffled) for the footprints in the layout excerpt that follows; sources: Cadence DE-HDL packaged netlist, KiCad conversion of 03242023_DA0F0TMBIJ0_F0T_Motherboard_J_brd_V01_OCP.brd

PR2  Q_RES  0 5% CHIP  pkg 0402LF  page 300 : A = GND ; B = GND
PL14  Q_INDUCTOR  100NH/16A IND  pkg SMLF  page 290 : \1\ = P12V_AUX ; \2\ = SW_P12V_PVCCFA_EHV_FIVRA_CPU1_R
R4142  Q_RES  4.7K 5% CHIP  pkg 0402LF  page 146 : A = P3V3_AUX ; B = PRSNT_CABLE_GPU_A2_ISO_N

(kicad_pcb
	(version 20260206)
	(generator "pcbnew")
	(generator_version "10.0")
	(general
		(thickness 1.6)
		(legacy_teardrops no)
	)
	(paper "A4")
	(title_block
		(title "03242023_DA0F0TMBIJ0_F0T_Motherboard_J_brd_V01_OCP.brd")
		(comment 1 "Grand Teton / footprints 845-847 of 6105")
	)
	(layers
		(0 "F.Cu" signal "TOP")
		(4 "In1.Cu" signal "GND")
		(6 "In2.Cu" signal "IN1")
		(8 "In3.Cu" signal "GND1")
		(10 "In4.Cu" signal "IN2")
		(12 "In5.Cu" signal "GND2")
		(14 "In6.Cu" signal "IN3")
		(16 "In7.Cu" signal "GND3")
		(18 "In8.Cu" signal "VCC")
		(20 "In9.Cu" signal "VCC1")
		(22 "In10.Cu" signal "GND4")
		(24 "In11.Cu" signal "IN4")
		(26 "In12.Cu" signal "GND5")
		(28 "In13.Cu" signal "IN5")
		(30 "In14.Cu" signal "GND6")
		(32 "In15.Cu" signal "IN6")
		(34 "In16.Cu" signal "GND7")
		(2 "B.Cu" signal "BOTTOM")
		(9 "F.Adhes" user "F.Adhesive")
		(11 "B.Adhes" user "B.Adhesive")
		(13 "F.Paste" user "Package Geometry/Pastemask Top")
		(15 "B.Paste" user "Package Geometry/Pastemask Bottom")
		(5 "F.SilkS" user "Ref Des/Silkscreen Top")
		(7 "B.SilkS" user "Ref Des/Silkscreen Bottom")
		(1 "F.Mask" user "Board Geometry/Soldermask Top")
		(3 "B.Mask" user "Board Geometry/Soldermask Bottom")
		(17 "Dwgs.User" user "User.Drawings")
		(19 "Cmts.User" user "User.Comments")
		(21 "Eco1.User" user "User.Eco1")
		(23 "Eco2.User" user "User.Eco2")
		(25 "Edge.Cuts" user "Board Geometry/Outline")
		(27 "Margin" user)
		(31 "F.CrtYd" user "Package Geometry/Place Bound Top")
		(29 "B.CrtYd" user "Package Geometry/Place Bound Bottom")
		(35 "F.Fab" user "Ref Des/Assembly Top")
		(33 "B.Fab" user "Ref Des/Assembly Bottom")
	)
	(footprint ""
		(layer "F.Cu")
		(at 306.83454 -433.0573 90)
		(property "Reference" "R4142"
			(at 0 0 90)
			(layer "F.SilkS")
			(hide yes)
			(effects
				(font
					(size 1.27 1.27)
				)
			)
		)
		(property "Value" ""
			(at 0 0 90)
			(layer "F.Fab")
			(effects
				(font
					(size 1.27 1.27)
				)
			)
		)
		(duplicate_pad_numbers_are_jumpers no)
		(fp_line
			(start 0.7874 -0.4064)
			(end 0.7874 0.4064)
			(stroke
				(width 0.1524)
				(type default)
			)
			(layer "F.SilkS")
		)
		(fp_line
			(start -0.7874 -0.4064)
			(end 0.7874 -0.4064)
			(stroke
				(width 0.1524)
				(type default)
			)
			(layer "F.SilkS")
		)
		(fp_line
			(start 0.7874 0.4064)
			(end -0.7874 0.4064)
			(stroke
				(width 0.1524)
				(type default)
			)
			(layer "F.SilkS")
		)
		(fp_line
			(start -0.7874 0.4064)
			(end -0.7874 -0.4064)
			(stroke
				(width 0.1524)
				(type default)
			)
			(layer "F.SilkS")
		)
		(fp_line
			(start -0.12065 -0.305054)
			(end -0.12065 -0.2794)
			(stroke
				(width 0.1)
				(type default)
			)
			(layer "F.Fab")
		)
		(fp_line
			(start -0.67945 -0.305054)
			(end -0.12065 -0.305054)
			(stroke
				(width 0.1)
				(type default)
			)
			(layer "F.Fab")
		)
		(fp_line
			(start 0.67945 -0.3048)
			(end 0.67945 0.3048)
			(stroke
				(width 0.1)
				(type default)
			)
			(layer "F.Fab")
		)
		(fp_line
			(start 0.12065 -0.3048)
			(end 0.67945 -0.3048)
			(stroke
				(width 0.1)
				(type default)
			)
			(layer "F.Fab")
		)
		(fp_line
			(start 0.12065 -0.2794)
			(end 0.12065 -0.3048)
			(stroke
				(width 0.1)
				(type default)
			)
			(layer "F.Fab")
		)
		(fp_line
			(start -0.12065 -0.2794)
			(end 0.12065 -0.2794)
			(stroke
				(width 0.1)
				(type default)
			)
			(layer "F.Fab")
		)
		(fp_line
			(start 0.120396 0.2794)
			(end -0.12065 0.2794)
			(stroke
				(width 0.1)
				(type default)
			)
			(layer "F.Fab")
		)
		(fp_line
			(start -0.12065 0.2794)
			(end -0.12065 0.3048)
			(stroke
				(width 0.1)
				(type default)
			)
			(layer "F.Fab")
		)
		(fp_line
			(start 0.67945 0.3048)
			(end 0.120396 0.3048)
			(stroke
				(width 0.1)
				(type default)
			)
			(layer "F.Fab")
		)
		(fp_line
			(start 0.120396 0.3048)
			(end 0.120396 0.2794)
			(stroke
				(width 0.1)
				(type default)
			)
			(layer "F.Fab")
		)
		(fp_line
			(start -0.12065 0.3048)
			(end -0.67945 0.3048)
			(stroke
				(width 0.1)
				(type default)
			)
			(layer "F.Fab")
		)
		(fp_line
			(start -0.67945 0.3048)
			(end -0.67945 -0.305054)
			(stroke
				(width 0.1)
				(type default)
			)
			(layer "F.Fab")
		)
		(pad "1" smd circle
			(at -0.40005 0 90)
			(size 0 0)
			(layers "F.Cu" "F.Mask" "F.Paste")
			(net "P3V3_AUX")
		)
		(pad "2" smd circle
			(at 0.40005 0 90)
			(size 0 0)
			(layers "F.Cu" "F.Mask" "F.Paste")
			(net "PRSNT_CABLE_GPU_A2_ISO_N")
		)
	)
	(footprint ""
		(layer "F.Cu")
		(at 23.392384 -176.82972 -90)
		(property "Reference" "PR2"
			(at 0 0 270)
			(layer "F.SilkS")
			(hide yes)
			(effects
				(font
					(size 1.27 1.27)
				)
			)
		)
		(property "Value" ""
			(at 0 0 270)
			(layer "F.Fab")
			(effects
				(font
					(size 1.27 1.27)
				)
			)
		)
		(duplicate_pad_numbers_are_jumpers no)
		(fp_line
			(start -0.7874 0.4064)
			(end -0.7874 -0.4064)
			(stroke
				(width 0.1524)
				(type default)
			)
			(layer "F.SilkS")
		)
		(fp_line
			(start 0.7874 0.4064)
			(end -0.7874 0.4064)
			(stroke
				(width 0.1524)
				(type default)
			)
			(layer "F.SilkS")
		)
		(fp_line
			(start -0.7874 -0.4064)
			(end 0.7874 -0.4064)
			(stroke
				(width 0.1524)
				(type default)
			)
			(layer "F.SilkS")
		)
		(fp_line
			(start 0.7874 -0.4064)
			(end 0.7874 0.4064)
			(stroke
				(width 0.1524)
				(type default)
			)
			(layer "F.SilkS")
		)
		(fp_line
			(start -0.67945 0.3048)
			(end -0.67945 -0.305054)
			(stroke
				(width 0.1)
				(type default)
			)
			(layer "F.Fab")
		)
		(fp_line
			(start -0.12065 0.3048)
			(end -0.67945 0.3048)
			(stroke
				(width 0.1)
				(type default)
			)
			(layer "F.Fab")
		)
		(fp_line
			(start 0.120396 0.3048)
			(end 0.120396 0.2794)
			(stroke
				(width 0.1)
				(type default)
			)
			(layer "F.Fab")
		)
		(fp_line
			(start 0.67945 0.3048)
			(end 0.120396 0.3048)
			(stroke
				(width 0.1)
				(type default)
			)
			(layer "F.Fab")
		)
		(fp_line
			(start -0.12065 0.2794)
			(end -0.12065 0.3048)
			(stroke
				(width 0.1)
				(type default)
			)
			(layer "F.Fab")
		)
		(fp_line
			(start 0.120396 0.2794)
			(end -0.12065 0.2794)
			(stroke
				(width 0.1)
				(type default)
			)
			(layer "F.Fab")
		)
		(fp_line
			(start -0.12065 -0.2794)
			(end 0.12065 -0.2794)
			(stroke
				(width 0.1)
				(type default)
			)
			(layer "F.Fab")
		)
		(fp_line
			(start 0.12065 -0.2794)
			(end 0.12065 -0.3048)
			(stroke
				(width 0.1)
				(type default)
			)
			(layer "F.Fab")
		)
		(fp_line
			(start 0.12065 -0.3048)
			(end 0.67945 -0.3048)
			(stroke
				(width 0.1)
				(type default)
			)
			(layer "F.Fab")
		)
		(fp_line
			(start 0.67945 -0.3048)
			(end 0.67945 0.3048)
			(stroke
				(width 0.1)
				(type default)
			)
			(layer "F.Fab")
		)
		(fp_line
			(start -0.67945 -0.305054)
			(end -0.12065 -0.305054)
			(stroke
				(width 0.1)
				(type default)
			)
			(layer "F.Fab")
		)
		(fp_line
			(start -0.12065 -0.305054)
			(end -0.12065 -0.2794)
			(stroke
				(width 0.1)
				(type default)
			)
			(layer "F.Fab")
		)
		(pad "1" smd circle
			(at -0.40005 0 270)
			(size 0 0)
			(layers "F.Cu" "F.Mask" "F.Paste")
			(net "GND")
		)
		(pad "2" smd circle
			(at 0.40005 0 270)
			(size 0 0)
			(layers "F.Cu" "F.Mask" "F.Paste")
			(net "GND")
		)
	)
	(footprint ""
		(layer "F.Cu")
		(at 174.112936 -363.249972)
		(property "Reference" "PL14"
			(at 0.844804 -3.134868 0)
			(unlocked yes)
			(layer "F.SilkS")
			(effects
				(font
					(size 0.7874 0.5842)
					(thickness 0.1524)
				)
				(justify left)
			)
		)
		(property "Value" ""
			(at 0 0 0)
			(layer "F.Fab")
			(effects
				(font
					(size 1.27 1.27)
				)
			)
		)
		(duplicate_pad_numbers_are_jumpers no)
		(fp_line
			(start -2.249932 -2.249932)
			(end 2.249932 -2.249932)
			(stroke
				(width 0.1524)
				(type default)
			)
			(layer "F.SilkS")
		)
		(fp_line
			(start -2.249932 -1.3843)
			(end -2.249932 -2.249932)
			(stroke
				(width 0.1524)
				(type default)
			)
			(layer "F.SilkS")
		)
		(fp_line
			(start -2.249932 2.249932)
			(end -2.249932 1.3843)
			(stroke
				(width 0.1524)
				(type default)
			)
			(layer "F.SilkS")
		)
		(fp_line
			(start 2.249932 -2.249932)
			(end 2.249932 -1.3843)
			(stroke
				(width 0.1524)
				(type default)
			)
			(layer "F.SilkS")
		)
		(fp_line
			(start 2.249932 1.3843)
			(end 2.249932 2.249932)
			(stroke
				(width 0.1524)
				(type default)
			)
			(layer "F.SilkS")
		)
		(fp_line
			(start 2.249932 2.249932)
			(end -2.249932 2.249932)
			(stroke
				(width 0.1524)
				(type default)
			)
			(layer "F.SilkS")
		)
		(fp_line
			(start -2.249932 -2.249932)
			(end 2.249932 -2.249932)
			(stroke
				(width 0.1)
				(type default)
			)
			(layer "F.Fab")
		)
		(fp_line
			(start -2.249932 2.249932)
			(end -2.249932 -2.249932)
			(stroke
				(width 0.1)
				(type default)
			)
			(layer "F.Fab")
		)
		(fp_line
			(start 2.249932 -2.249932)
			(end 2.249932 2.249932)
			(stroke
				(width 0.1)
				(type default)
			)
			(layer "F.Fab")
		)
		(fp_line
			(start 2.249932 2.249932)
			(end -2.249932 2.249932)
			(stroke
				(width 0.1)
				(type default)
			)
			(layer "F.Fab")
		)
		(pad "1" smd rect
			(at -1.82499 0)
			(size 1.0668 2.5146)
			(layers "F.Cu" "F.Mask" "F.Paste")
			(net "P12V_AUX")
		)
		(pad "2" smd rect
			(at 1.82499 0)
			(size 1.0668 2.5146)
			(layers "F.Cu" "F.Mask" "F.Paste")
			(net "SW_P12V_PVCCFA_EHV_FIVRA_CPU1_R")
		)
	)
)
